# BASEBOARD_FAB2 (Tioga Pass) — schematic netlist excerpt (pin names and nets, part order shuffled) for the footprints in the layout excerpt that follows; sources: Cadence DE-HDL packaged netlist, KiCad conversion of Wiwynn_Tioga_Pass_MB.brd

C8L11  CAP  100UF 4V 20% X5R  pkg 0805  page 228 : A = PVDDQ_KLM ; B = GND
C2N20  CAP_A  1.0UF 6.3V 10% X6S  pkg 0402V  page 130 : A = P3V3_STBY ; B = GND
C5G60  CAP_A  22.0UF 4V 20% X6S  pkg 0603V  page 242 : A = PVDDQ_DEF ; B = GND

(kicad_pcb
	(version 20260206)
	(generator "pcbnew")
	(generator_version "10.0")
	(general
		(thickness 1.6)
		(legacy_teardrops no)
	)
	(paper "A4")
	(title_block
		(title "Wiwynn_Tioga_Pass_MB.brd")
		(comment 1 "Tioga Pass / footprints 2742-2744 of 4770")
	)
	(layers
		(0 "F.Cu" signal "TOP")
		(4 "In1.Cu" signal "L2GND")
		(6 "In2.Cu" signal "L3")
		(8 "In3.Cu" signal "L4GND")
		(10 "In4.Cu" signal "L5")
		(12 "In5.Cu" signal "L6GND")
		(14 "In6.Cu" signal "L7VCC")
		(16 "In7.Cu" signal "L8VCC")
		(18 "In8.Cu" signal "L9GND")
		(20 "In9.Cu" signal "L10")
		(22 "In10.Cu" signal "L11GND")
		(24 "In11.Cu" signal "L12")
		(26 "In12.Cu" signal "L13GND")
		(2 "B.Cu" signal "BOTTOM")
		(9 "F.Adhes" user "F.Adhesive")
		(11 "B.Adhes" user "B.Adhesive")
		(13 "F.Paste" user "Package Geometry/Pastemask Top")
		(15 "B.Paste" user "Package Geometry/Pastemask Bottom")
		(5 "F.SilkS" user "Ref Des/Silkscreen Top")
		(7 "B.SilkS" user "Ref Des/Silkscreen Bottom")
		(1 "F.Mask" user "Board Geometry/Soldermask Top")
		(3 "B.Mask" user "Board Geometry/Soldermask Bottom")
		(17 "Dwgs.User" user "User.Drawings")
		(19 "Cmts.User" user "User.Comments")
		(21 "Eco1.User" user "User.Eco1")
		(23 "Eco2.User" user "User.Eco2")
		(25 "Edge.Cuts" user "Board Geometry/Outline")
		(27 "Margin" user)
		(31 "F.CrtYd" user "Package Geometry/Place Bound Top")
		(29 "B.CrtYd" user "Package Geometry/Place Bound Bottom")
		(35 "F.Fab" user "Ref Des/Assembly Top")
		(33 "B.Fab" user "Ref Des/Assembly Bottom")
	)
	(footprint ""
		(layer "B.Cu")
		(at 248.8565 -149.8092 -90)
		(property "Reference" "C5G60"
			(at -1.14681 0.76708 0)
			(unlocked yes)
			(layer "B.SilkS")
			(effects
				(font
					(size 0.7874 0.5842)
					(thickness 0.1524)
				)
				(justify mirror)
			)
		)
		(property "Value" ""
			(at 0 0 90)
			(layer "B.Fab")
			(effects
				(font
					(size 1.27 1.27)
				)
				(justify mirror)
			)
		)
		(duplicate_pad_numbers_are_jumpers no)
		(fp_rect
			(start 0.4953 1.6002)
			(end -0.4953 -0.2032)
			(stroke
				(width 0)
				(type default)
			)
			(fill no)
			(layer "B.CrtYd")
		)
		(fp_line
			(start -0.4953 1.6002)
			(end 0.4953 1.6002)
			(stroke
				(width 0.1)
				(type default)
			)
			(layer "B.Fab")
		)
		(fp_line
			(start 0.4953 1.6002)
			(end 0.4953 -0.2032)
			(stroke
				(width 0.1)
				(type default)
			)
			(layer "B.Fab")
		)
		(fp_line
			(start -0.4953 -0.2032)
			(end -0.4953 1.6002)
			(stroke
				(width 0.1)
				(type default)
			)
			(layer "B.Fab")
		)
		(fp_line
			(start 0.4953 -0.2032)
			(end -0.4953 -0.2032)
			(stroke
				(width 0.1)
				(type default)
			)
			(layer "B.Fab")
		)
		(pad "1" smd rect
			(at 0 0 90)
			(size 0.762 0.889)
			(layers "B.Cu" "B.Mask" "B.Paste")
			(net "PVDDQ_DEF")
		)
		(pad "2" smd rect
			(at 0 1.397 90)
			(size 0.762 0.889)
			(layers "B.Cu" "B.Mask" "B.Paste")
			(net "GND")
		)
		(zone
			(layer "B.Cu")
			(hatch none 0.5)
			(connect_pads
				(clearance 0)
			)
			(min_thickness 0.25)
			(keepout
				(tracks not_allowed)
				(vias allowed)
				(pads allowed)
				(copperpour not_allowed)
				(footprints allowed)
			)
			(placement
				(enabled no)
				(sheetname "")
			)
			(fill
				(thermal_gap 0.5)
				(thermal_bridge_width 0.5)
				(island_removal_mode 0)
			)
			(polygon
				(pts
					(xy 247.904 -149.4282) (xy 248.412 -149.4282) (xy 248.412 -150.1902) (xy 247.904 -150.1902)
				)
			)
		)
	)
	(footprint ""
		(layer "B.Cu")
		(at 389.509 -104.4702 -90)
		(property "Reference" "C2N20"
			(at 0 0 90)
			(layer "B.SilkS")
			(hide yes)
			(effects
				(font
					(size 1.27 1.27)
				)
				(justify mirror)
			)
		)
		(property "Value" ""
			(at 0 0 90)
			(layer "B.Fab")
			(effects
				(font
					(size 1.27 1.27)
				)
				(justify mirror)
			)
		)
		(duplicate_pad_numbers_are_jumpers no)
		(fp_rect
			(start 0.2794 0.9144)
			(end -0.2794 -0.1143)
			(stroke
				(width 0)
				(type default)
			)
			(fill no)
			(layer "B.CrtYd")
		)
		(fp_line
			(start -0.2794 0.9144)
			(end 0.2794 0.9144)
			(stroke
				(width 0.1)
				(type default)
			)
			(layer "B.Fab")
		)
		(fp_line
			(start 0.2794 0.9144)
			(end 0.2794 -0.1143)
			(stroke
				(width 0.1)
				(type default)
			)
			(layer "B.Fab")
		)
		(fp_line
			(start -0.2794 -0.1143)
			(end -0.2794 0.9144)
			(stroke
				(width 0.1)
				(type default)
			)
			(layer "B.Fab")
		)
		(fp_line
			(start 0.2794 -0.1143)
			(end -0.2794 -0.1143)
			(stroke
				(width 0.1)
				(type default)
			)
			(layer "B.Fab")
		)
		(pad "1" smd custom
			(at 0 0 180)
			(size 0.10414 0.10414)
			(layers "B.Cu" "B.Mask" "B.Paste")
			(net "P3V3_STBY")
			(options
				(clearance outline)
				(anchor circle)
			)
			(primitives
				(gr_poly
					(pts
						(xy -0.20828 -0.08636) (xy -0.20828 0.08636) (xy -0.08636 0.20828) (xy 0.086614 0.20828) (xy 0.20828 0.086614)
						(xy 0.20828 -0.08636) (xy 0.08636 -0.20828) (xy -0.08636 -0.20828)
					)
					(width 0)
					(fill yes)
				)
			)
		)
		(pad "2" smd custom
			(at 0 0.8001 180)
			(size 0.10414 0.10414)
			(layers "B.Cu" "B.Mask" "B.Paste")
			(net "GND")
			(options
				(clearance outline)
				(anchor circle)
			)
			(primitives
				(gr_poly
					(pts
						(xy -0.20828 -0.08636) (xy -0.20828 0.08636) (xy -0.08636 0.20828) (xy 0.086614 0.20828) (xy 0.20828 0.086614)
						(xy 0.20828 -0.08636) (xy 0.08636 -0.20828) (xy -0.08636 -0.20828)
					)
					(width 0)
					(fill yes)
				)
			)
		)
		(zone
			(layer "B.Cu")
			(hatch none 0.5)
			(connect_pads
				(clearance 0)
			)
			(min_thickness 0.25)
			(keepout
				(tracks allowed)
				(vias not_allowed)
				(pads allowed)
				(copperpour not_allowed)
				(footprints allowed)
			)
			(placement
				(enabled no)
				(sheetname "")
			)
			(fill
				(thermal_gap 0.5)
				(thermal_bridge_width 0.5)
				(island_removal_mode 0)
			)
			(polygon
				(pts
					(xy 389.29945 -104.38257) (xy 388.91845 -104.38257) (xy 388.91845 -104.55783) (xy 389.29945 -104.558084)
				)
			)
		)
		(zone
			(layer "B.Cu")
			(hatch none 0.5)
			(connect_pads
				(clearance 0)
			)
			(min_thickness 0.25)
			(keepout
				(tracks not_allowed)
				(vias allowed)
				(pads allowed)
				(copperpour not_allowed)
				(footprints allowed)
			)
			(placement
				(enabled no)
				(sheetname "")
			)
			(fill
				(thermal_gap 0.5)
				(thermal_bridge_width 0.5)
				(island_removal_mode 0)
			)
			(polygon
				(pts
					(xy 389.29945 -104.38257) (xy 388.91845 -104.38257) (xy 388.91845 -104.55783) (xy 389.29945 -104.558084)
				)
			)
		)
	)
	(footprint ""
		(layer "B.Cu")
		(at 94.292928 -144.987772 90)
		(property "Reference" "C8L11"
			(at 0 0 90)
			(layer "B.SilkS")
			(hide yes)
			(effects
				(font
					(size 1.27 1.27)
				)
				(justify mirror)
			)
		)
		(property "Value" ""
			(at 0 0 90)
			(layer "B.Fab")
			(effects
				(font
					(size 1.27 1.27)
				)
				(justify mirror)
			)
		)
		(duplicate_pad_numbers_are_jumpers no)
		(fp_poly
			(pts
				(xy 0.7239 -0.2159) (xy -0.7239 -0.2159) (xy -0.7239 1.9939) (xy 0.7239 1.9939)
			)
			(stroke
				(width 0)
				(type default)
			)
			(fill no)
			(layer "B.CrtYd")
		)
		(fp_line
			(start 0.7239 -0.2159)
			(end 0.7239 1.9939)
			(stroke
				(width 0.1)
				(type default)
			)
			(layer "B.Fab")
		)
		(fp_line
			(start -0.7239 -0.2159)
			(end 0.7239 -0.2159)
			(stroke
				(width 0.1)
				(type default)
			)
			(layer "B.Fab")
		)
		(fp_line
			(start 0.7239 1.9939)
			(end -0.7239 1.9939)
			(stroke
				(width 0.1)
				(type default)
			)
			(layer "B.Fab")
		)
		(fp_line
			(start -0.7239 1.9939)
			(end -0.7239 -0.2159)
			(stroke
				(width 0.1)
				(type default)
			)
			(layer "B.Fab")
		)
		(pad "1" smd rect
			(at 0 0 270)
			(size 1.27 1.016)
			(layers "B.Cu" "B.Mask" "B.Paste")
			(net "PVDDQ_KLM")
		)
		(pad "2" smd rect
			(at 0 1.778 270)
			(size 1.27 1.016)
			(layers "B.Cu" "B.Mask" "B.Paste")
			(net "GND")
		)
		(zone
			(layer "B.Cu")
			(hatch none 0.5)
			(connect_pads
				(clearance 0)
			)
			(min_thickness 0.25)
			(keepout
				(tracks not_allowed)
				(vias allowed)
				(pads allowed)
				(copperpour not_allowed)
				(footprints allowed)
			)
			(placement
				(enabled no)
				(sheetname "")
			)
			(fill
				(thermal_gap 0.5)
				(thermal_bridge_width 0.5)
				(island_removal_mode 0)
			)
			(polygon
				(pts
					(xy 94.800928 -145.622772) (xy 94.800928 -144.352772) (xy 95.562928 -144.352772) (xy 95.562928 -145.622772)
				)
			)
		)
	)
)
